FILE_TYPE=LIBRARY_PARTS;
primitive 'TP';
  pin
    'TP':
      PIN_NUMBER='(1)';
  end_pin;
  body
    PART_NAME='TP';
    BODY_NAME='tp';
    PHYS_DES_PREFIX='TP';
 end_body;
end_primitive;
END.
